(kicad_pcb
	(version 20240108)
	(generator "pcbnew")
	(generator_version "8.0")
	(general
		(thickness 1.586)
		(legacy_teardrops no)
	)
	(paper "A4")
	(title_block
		(title "GMSL Serializer")
		(date "2024-11-27")
		(rev "1.1.1")
		(company "Antmicro Ltd")
		(comment 1 "www.antmicro.com")
		(comment 9 "footprints 44-48 of 117")
	)
	(layers
		(0 "F.Cu" signal)
		(1 "In1.Cu" power)
		(2 "In2.Cu" power)
		(31 "B.Cu" signal)
		(32 "B.Adhes" user "B.Adhesive")
		(33 "F.Adhes" user "F.Adhesive")
		(34 "B.Paste" user)
		(35 "F.Paste" user)
		(36 "B.SilkS" user "B.Silkscreen")
		(37 "F.SilkS" user "F.Silkscreen")
		(38 "B.Mask" user)
		(39 "F.Mask" user)
		(40 "Dwgs.User" user "User.Drawings")
		(41 "Cmts.User" user "User.Comments")
		(42 "Eco1.User" user "User.Eco1")
		(43 "Eco2.User" user "User.Eco2")
		(44 "Edge.Cuts" user)
		(45 "Margin" user)
		(46 "B.CrtYd" user "B.Courtyard")
		(47 "F.CrtYd" user "F.Courtyard")
		(48 "B.Fab" user)
		(49 "F.Fab" user)
	)
	(footprint "antmicro-footprints:D_0402_1005Metric"
		(layer "F.Cu")
		(at 152.497391 98.049759 -45)
		(property "Reference" "D2"
			(at -0.740447 -2.830102 -45)
			(unlocked yes)
			(layer "F.SilkS")
			(effects
				(font
					(size 0.7 0.7)
					(thickness 0.15)
				)
				(justify left bottom)
			)
		)
		(property "Value" "AXGD10402KR"
			(at -2.54 2.54 -45)
			(layer "F.Fab")
			(effects
				(font
					(size 0.7 0.7)
					(thickness 0.15)
				)
				(justify left bottom)
			)
		)
		(property "Footprint" "antmicro-footprints:D_0402_1005Metric"
			(at 0 0 -45)
			(layer "F.Fab")
			(hide yes)
			(effects
				(font
					(size 1.27 1.27)
					(thickness 0.15)
				)
			)
		)
		(property "Datasheet" "https://www.littelfuse.com/media?resourcetype=datasheets&itemid=020b2bf2-064c-4ff1-a898-b4ec805b2fea&filename=littelfuse-xtremeguard-axgd-datasheet"
			(at 0 0 -45)
			(layer "F.Fab")
			(hide yes)
			(effects
				(font
					(size 1.27 1.27)
					(thickness 0.15)
				)
			)
		)
		(property "Author" "Antmicro"
			(at -24.666197 136.550049 0)
			(layer "F.Fab")
			(hide yes)
			(effects
				(font
					(size 1 1)
					(thickness 0.15)
				)
			)
		)
		(property "License" "Apache-2.0"
			(at -24.666197 136.550049 0)
			(layer "F.Fab")
			(hide yes)
			(effects
				(font
					(size 1 1)
					(thickness 0.15)
				)
			)
		)
		(property "MPN" "AXGD10402KR"
			(at -24.666197 136.550049 0)
			(layer "F.Fab")
			(hide yes)
			(effects
				(font
					(size 1 1)
					(thickness 0.15)
				)
			)
		)
		(property "Manufacturer" "Littelfuse"
			(at -24.666197 136.550049 0)
			(layer "F.Fab")
			(hide yes)
			(effects
				(font
					(size 1 1)
					(thickness 0.15)
				)
			)
		)
		(sheetname "GMSL Connector")
		(sheetfile "GMSL.kicad_sch")
		(attr smd)
		(fp_line
			(start -0.875 -0.25)
			(end -0.875 0.25)
			(stroke
				(width 0.15)
				(type solid)
			)
			(layer "F.SilkS")
		)
		(fp_line
			(start -0.1 0.255)
			(end 0.1 0.255)
			(stroke
				(width 0.15)
				(type solid)
			)
			(layer "F.SilkS")
		)
		(fp_line
			(start 0.1 -0.255)
			(end -0.1 -0.255)
			(stroke
				(width 0.15)
				(type solid)
			)
			(layer "F.SilkS")
		)
		(fp_poly
			(pts
				(xy -0.925 -0.47) (xy 0.925 -0.47) (xy 0.925 0.47) (xy -0.925 0.47)
			)
			(stroke
				(width 0.05)
				(type default)
			)
			(fill none)
			(layer "F.CrtYd")
		)
		(fp_line
			(start -0.51 0.255)
			(end -0.51 -0.255)
			(stroke
				(width 0.15)
				(type solid)
			)
			(layer "F.Fab")
		)
		(fp_line
			(start -0.51 -0.255)
			(end 0.51 -0.255)
			(stroke
				(width 0.15)
				(type solid)
			)
			(layer "F.Fab")
		)
		(fp_line
			(start -0.2 -0.25)
			(end -0.5 0.05)
			(stroke
				(width 0.15)
				(type solid)
			)
			(layer "F.Fab")
		)
		(fp_line
			(start 0.51 0.255)
			(end -0.51 0.255)
			(stroke
				(width 0.15)
				(type solid)
			)
			(layer "F.Fab")
		)
		(fp_line
			(start 0.51 -0.255)
			(end 0.51 0.255)
			(stroke
				(width 0.15)
				(type solid)
			)
			(layer "F.Fab")
		)
		(fp_text user "Author: Antmicro"
			(at -2.54 6.94 -45)
			(layer "F.Fab")
			(hide yes)
			(effects
				(font
					(size 0.7 0.7)
					(thickness 0.15)
				)
				(justify left bottom)
			)
		)
		(fp_text user "${REFERENCE}"
			(at -2.54 4.54 -45)
			(layer "F.Fab")
			(hide yes)
			(effects
				(font
					(size 0.7 0.7)
					(thickness 0.15)
				)
				(justify left bottom)
			)
		)
		(fp_text user "License: Apache-2.0"
			(at -2.54 5.74 -45)
			(layer "F.Fab")
			(hide yes)
			(effects
				(font
					(size 0.7 0.7)
					(thickness 0.15)
				)
				(justify left bottom)
			)
		)
		(pad "1" smd roundrect
			(at -0.48 0 315)
			(size 0.59 0.64)
			(layers "F.Cu" "F.Paste" "F.Mask")
			(roundrect_rratio 0.25)
			(net 18 "/GMSL Connector/SIO_P")
			(pinfunction "C")
			(pintype "passive")
		)
		(pad "2" smd roundrect
			(at 0.48 0 315)
			(size 0.59 0.64)
			(layers "F.Cu" "F.Paste" "F.Mask")
			(roundrect_rratio 0.25)
			(net 1 "GND")
			(pinfunction "A")
			(pintype "passive")
		)
	)
	(footprint "antmicro-footprints:R_0402_1005Metric"
		(layer "F.Cu")
		(at 133.1 107.7)
		(descr "Resistor SMD 0402")
		(tags "resistor SMD 0402")
		(property "Reference" "R3"
			(at 1.05 -5.133332 0)
			(layer "F.SilkS")
			(effects
				(font
					(size 0.7 0.7)
					(thickness 0.15)
				)
				(justify left bottom)
			)
		)
		(property "Value" "R_100R_0402"
			(at -1.011843 1.772047 0)
			(layer "F.Fab")
			(effects
				(font
					(size 0.7 0.7)
					(thickness 0.15)
				)
				(justify left bottom)
			)
		)
		(property "Footprint" "antmicro-footprints:R_0402_1005Metric"
			(at 0 0 0)
			(layer "F.Fab")
			(hide yes)
			(effects
				(font
					(size 1.27 1.27)
					(thickness 0.15)
				)
			)
		)
		(property "Datasheet" "https://www.bourns.com/docs/product-datasheets/cr.pdf"
			(at 0 0 0)
			(layer "F.Fab")
			(hide yes)
			(effects
				(font
					(size 1.27 1.27)
					(thickness 0.15)
				)
			)
		)
		(property "Author" "Antmicro"
			(at 0 0 0)
			(layer "F.Fab")
			(hide yes)
			(effects
				(font
					(size 1 1)
					(thickness 0.15)
				)
			)
		)
		(property "License" "Apache-2.0"
			(at 0 0 0)
			(layer "F.Fab")
			(hide yes)
			(effects
				(font
					(size 1 1)
					(thickness 0.15)
				)
			)
		)
		(property "MPN" "CR0402-FX-1000GLF"
			(at 0 0 0)
			(layer "F.Fab")
			(hide yes)
			(effects
				(font
					(size 1 1)
					(thickness 0.15)
				)
			)
		)
		(property "Manufacturer" "Bourns"
			(at 0 0 0)
			(layer "F.Fab")
			(hide yes)
			(effects
				(font
					(size 1 1)
					(thickness 0.15)
				)
			)
		)
		(property "Tolerance" "1%"
			(at 0 0 0)
			(layer "F.Fab")
			(hide yes)
			(effects
				(font
					(size 1 1)
					(thickness 0.15)
				)
			)
		)
		(property "Val" "100R"
			(at 0 0 0)
			(layer "F.Fab")
			(hide yes)
			(effects
				(font
					(size 1 1)
					(thickness 0.15)
				)
			)
		)
		(sheetname "CSI Connector")
		(sheetfile "CSI.kicad_sch")
		(attr smd)
		(fp_rect
			(start -0.925 -0.47)
			(end 0.925 0.47)
			(stroke
				(width 0.05)
				(type default)
			)
			(fill none)
			(layer "F.CrtYd")
		)
		(fp_rect
			(start -0.5 -0.25)
			(end 0.5 0.25)
			(stroke
				(width 0.15)
				(type solid)
			)
			(fill none)
			(layer "F.Fab")
		)
		(fp_text user "${REFERENCE}"
			(at -0.95 3.168 0)
			(layer "F.Fab")
			(hide yes)
			(effects
				(font
					(size 0.7 0.7)
					(thickness 0.15)
				)
				(justify left bottom)
			)
		)
		(fp_text user "Author: Antmicro"
			(at -0.95 4.169 0)
			(layer "F.Fab")
			(hide yes)
			(effects
				(font
					(size 0.7 0.7)
					(thickness 0.15)
				)
				(justify left bottom)
			)
		)
		(fp_text user "License: Apache-2.0"
			(at -0.95 5.169 0)
			(layer "F.Fab")
			(hide yes)
			(effects
				(font
					(size 0.7 0.7)
					(thickness 0.15)
				)
				(justify left bottom)
			)
		)
		(pad "1" smd roundrect
			(at -0.48 0)
			(size 0.59 0.64)
			(layers "F.Cu" "F.Paste" "F.Mask")
			(roundrect_rratio 0.25)
			(net 34 "/CSI Connector/SDA_CAM0")
			(pintype "passive")
		)
		(pad "2" smd roundrect
			(at 0.48 0)
			(size 0.59 0.64)
			(layers "F.Cu" "F.Paste" "F.Mask")
			(roundrect_rratio 0.25)
			(net 88 "/CSI Connector/I2C.SDA")
			(pintype "passive")
		)
	)
	(footprint "antmicro-footprints:C_0402_1005Metric"
		(layer "F.Cu")
		(at 155.2 107.362 90)
		(descr "Capacitor SMD 0402")
		(tags "capacitor SMD 0402")
		(property "Reference" "C15"
			(at -1.088 -0.4 90)
			(layer "F.SilkS")
			(effects
				(font
					(size 0.7 0.7)
					(thickness 0.15)
				)
				(justify left bottom)
			)
		)
		(property "Value" "C_1u_16V_0402"
			(at -1.022927 2.155213 90)
			(layer "F.Fab")
			(effects
				(font
					(size 0.7 0.7)
					(thickness 0.15)
				)
				(justify left bottom)
			)
		)
		(property "Footprint" "antmicro-footprints:C_0402_1005Metric"
			(at 0 0 90)
			(layer "F.Fab")
			(hide yes)
			(effects
				(font
					(size 1.27 1.27)
					(thickness 0.15)
				)
			)
		)
		(property "Datasheet" "https://www.kemet.com/en/us/capacitors/product/C0402C105M4PACTU.html"
			(at 0 0 90)
			(layer "F.Fab")
			(hide yes)
			(effects
				(font
					(size 1.27 1.27)
					(thickness 0.15)
				)
			)
		)
		(property "Author" "Antmicro"
			(at 262.562 -47.838 0)
			(layer "F.Fab")
			(hide yes)
			(effects
				(font
					(size 1 1)
					(thickness 0.15)
				)
			)
		)
		(property "Dielectric" ""
			(at 262.562 -47.838 0)
			(layer "F.Fab")
			(hide yes)
			(effects
				(font
					(size 1 1)
					(thickness 0.15)
				)
			)
		)
		(property "License" "Apache-2.0"
			(at 262.562 -47.838 0)
			(layer "F.Fab")
			(hide yes)
			(effects
				(font
					(size 1 1)
					(thickness 0.15)
				)
			)
		)
		(property "MPN" "C0402C105M4PACTU"
			(at 262.562 -47.838 0)
			(layer "F.Fab")
			(hide yes)
			(effects
				(font
					(size 1 1)
					(thickness 0.15)
				)
			)
		)
		(property "Manufacturer" "KEMET"
			(at 262.562 -47.838 0)
			(layer "F.Fab")
			(hide yes)
			(effects
				(font
					(size 1 1)
					(thickness 0.15)
				)
			)
		)
		(property "Val" "1u"
			(at 262.562 -47.838 0)
			(layer "F.Fab")
			(hide yes)
			(effects
				(font
					(size 1 1)
					(thickness 0.15)
				)
			)
		)
		(property "Voltage" "16V"
			(at 262.562 -47.838 0)
			(layer "F.Fab")
			(hide yes)
			(effects
				(font
					(size 1 1)
					(thickness 0.15)
				)
			)
		)
		(sheetname "Supply")
		(sheetfile "supply.kicad_sch")
		(attr smd)
		(fp_rect
			(start -0.925 -0.47)
			(end 0.925 0.47)
			(stroke
				(width 0.05)
				(type default)
			)
			(fill none)
			(layer "F.CrtYd")
		)
		(fp_line
			(start 0.504 -0.25)
			(end 0.504 0.248)
			(stroke
				(width 0.15)
				(type solid)
			)
			(layer "F.Fab")
		)
		(fp_line
			(start -0.494 -0.25)
			(end 0.504 -0.25)
			(stroke
				(width 0.15)
				(type solid)
			)
			(layer "F.Fab")
		)
		(fp_line
			(start 0.504 0.248)
			(end -0.494 0.248)
			(stroke
				(width 0.15)
				(type solid)
			)
			(layer "F.Fab")
		)
		(fp_line
			(start -0.494 0.248)
			(end -0.494 -0.25)
			(stroke
				(width 0.15)
				(type solid)
			)
			(layer "F.Fab")
		)
		(fp_text user "${REFERENCE}"
			(at -0.939 4.599 90)
			(layer "F.Fab")
			(hide yes)
			(effects
				(font
					(size 0.7 0.7)
					(thickness 0.15)
				)
				(justify left bottom)
			)
		)
		(fp_text user "License: Apache-2.0"
			(at -0.939 5.799 90)
			(layer "F.Fab")
			(hide yes)
			(effects
				(font
					(size 0.7 0.7)
					(thickness 0.15)
				)
				(justify left bottom)
			)
		)
		(fp_text user "Author: Antmicro"
			(at -0.939 3.399 90)
			(layer "F.Fab")
			(hide yes)
			(effects
				(font
					(size 0.7 0.7)
					(thickness 0.15)
				)
				(justify left bottom)
			)
		)
		(pad "1" smd roundrect
			(at -0.48 0 90)
			(size 0.59 0.64)
			(layers "F.Cu" "F.Paste" "F.Mask")
			(roundrect_rratio 0.25)
			(net 1 "GND")
			(pintype "passive")
		)
		(pad "2" smd roundrect
			(at 0.48 0 90)
			(size 0.59 0.64)
			(layers "F.Cu" "F.Paste" "F.Mask")
			(roundrect_rratio 0.25)
			(net 12 "+1V2")
			(pintype "passive")
		)
	)
	(footprint "antmicro-footprints:TP_SMD_1.5mm"
		(layer "F.Cu")
		(at 156 118)
		(property "Reference" "TP8"
			(at -0.4 -1 0)
			(layer "F.SilkS")
			(hide yes)
			(effects
				(font
					(size 0.7 0.7)
					(thickness 0.15)
				)
				(justify left bottom)
			)
		)
		(property "Value" "TP_1.5mm_SMD"
			(at 0 1.7 0)
			(layer "F.Fab")
			(effects
				(font
					(size 0.7 0.7)
					(thickness 0.15)
				)
				(justify left bottom)
			)
		)
		(property "Footprint" "antmicro-footprints:TP_SMD_1.5mm"
			(at 0 0 0)
			(layer "F.Fab")
			(hide yes)
			(effects
				(font
					(size 1.27 1.27)
					(thickness 0.15)
				)
			)
		)
		(property "Author" "Antmicro"
			(at 0 0 0)
			(layer "F.Fab")
			(hide yes)
			(effects
				(font
					(size 1 1)
					(thickness 0.15)
				)
			)
		)
		(property "License" "Apache-2.0"
			(at 0 0 0)
			(layer "F.Fab")
			(hide yes)
			(effects
				(font
					(size 1 1)
					(thickness 0.15)
				)
			)
		)
		(property "MPN" ""
			(at 0 0 0)
			(layer "F.Fab")
			(hide yes)
			(effects
				(font
					(size 1 1)
					(thickness 0.15)
				)
			)
		)
		(property "Manufacturer" ""
			(at 0 0 0)
			(layer "F.Fab")
			(hide yes)
			(effects
				(font
					(size 1 1)
					(thickness 0.15)
				)
			)
		)
		(sheetname "Serializer")
		(sheetfile "serializer.kicad_sch")
		(attr exclude_from_pos_files exclude_from_bom)
		(fp_circle
			(center 0 0)
			(end 0.85 0)
			(stroke
				(width 0.05)
				(type default)
			)
			(fill none)
			(layer "F.CrtYd")
		)
		(fp_text user "${REFERENCE}"
			(at -0.7 2.9 0)
			(layer "F.Fab")
			(hide yes)
			(effects
				(font
					(size 0.7 0.7)
					(thickness 0.15)
				)
				(justify left bottom)
			)
		)
		(fp_text user "Author: Antmicro"
			(at -0.7 4.101 0)
			(layer "F.Fab")
			(hide yes)
			(effects
				(font
					(size 0.7 0.7)
					(thickness 0.15)
				)
				(justify left bottom)
			)
		)
		(fp_text user "License: Apache-2.0"
			(at -0.7 5.301 0)
			(layer "F.Fab")
			(hide yes)
			(effects
				(font
					(size 0.7 0.7)
					(thickness 0.15)
				)
				(justify left bottom)
			)
		)
		(pad "1" smd circle
			(at 0 0 270)
			(size 1.5 1.5)
			(layers "F.Cu" "F.Mask")
			(net 85 "Net-(U6-MFP6)")
			(pinfunction "1")
			(pintype "passive")
		)
	)
	(footprint "antmicro-footprints:SOT-23-5"
		(layer "F.Cu")
		(at 157.686 105.927 180)
		(property "Reference" "U5"
			(at -0.642 1.875 0)
			(layer "F.SilkS")
			(effects
				(font
					(size 0.7 0.7)
					(thickness 0.15)
				)
				(justify right bottom)
			)
		)
		(property "Value" "TLV73312PDBVT"
			(at 0.002 2.799 0)
			(layer "F.Fab")
			(effects
				(font
					(size 0.7 0.7)
					(thickness 0.15)
				)
				(justify right bottom)
			)
		)
		(property "Footprint" "antmicro-footprints:SOT-23-5"
			(at 0 0 180)
			(layer "F.Fab")
			(hide yes)
			(effects
				(font
					(size 1.27 1.27)
					(thickness 0.15)
				)
			)
		)
		(property "Datasheet" "https://www.ti.com/lit/ds/symlink/tlv733p.pdf?HQS=dis-mous-null-mousermode-dsf-pf-null-wwe&ts=1676978230940&ref_url=https%253A%252F%252Fwww.mouser.com%252F"
			(at 0 0 180)
			(layer "F.Fab")
			(hide yes)
			(effects
				(font
					(size 1.27 1.27)
					(thickness 0.15)
				)
			)
		)
		(property "Author" "Antmicro"
			(at 315.372 211.854 0)
			(layer "F.Fab")
			(hide yes)
			(effects
				(font
					(size 1 1)
					(thickness 0.15)
				)
			)
		)
		(property "License" "Apache-2.0"
			(at 315.372 211.854 0)
			(layer "F.Fab")
			(hide yes)
			(effects
				(font
					(size 1 1)
					(thickness 0.15)
				)
			)
		)
		(property "MPN" "TLV73312PDBVT"
			(at 315.372 211.854 0)
			(layer "F.Fab")
			(hide yes)
			(effects
				(font
					(size 1 1)
					(thickness 0.15)
				)
			)
		)
		(property "Manufacturer" "Texas Instruments"
			(at 315.372 211.854 0)
			(layer "F.Fab")
			(hide yes)
			(effects
				(font
					(size 1 1)
					(thickness 0.15)
				)
			)
		)
		(sheetname "Supply")
		(sheetfile "supply.kicad_sch")
		(attr smd)
		(fp_line
			(start 0.8 1.599)
			(end 0.549 1.599)
			(stroke
				(width 0.15)
				(type solid)
			)
			(layer "F.SilkS")
		)
		(fp_line
			(start 0.8 1.3)
			(end 0.8 1.599)
			(stroke
				(width 0.15)
				(type solid)
			)
			(layer "F.SilkS")
		)
		(fp_line
			(start 0.8 0.55)
			(end 0.8 -0.55)
			(stroke
				(width 0.15)
				(type solid)
			)
			(layer "F.SilkS")
		)
		(fp_line
			(start 0.8 -1.3)
			(end 0.8 -1.6)
			(stroke
				(width 0.15)
				(type solid)
			)
			(layer "F.SilkS")
		)
		(fp_line
			(start 0.8 -1.6)
			(end 0.5 -1.6)
			(stroke
				(width 0.15)
				(type solid)
			)
			(layer "F.SilkS")
		)
		(fp_line
			(start -0.55 1.6)
			(end -0.85 1.6)
			(stroke
				(width 0.15)
				(type solid)
			)
			(layer "F.SilkS")
		)
		(fp_line
			(start -0.8 -1.6)
			(end -0.5 -1.6)
			(stroke
				(width 0.15)
				(type solid)
			)
			(layer "F.SilkS")
		)
		(fp_line
			(start -0.8 -1.6)
			(end -0.8 -1.3)
			(stroke
				(width 0.15)
				(type solid)
			)
			(layer "F.SilkS")
		)
		(fp_line
			(start -0.85 1.6)
			(end -0.85 1.301)
			(stroke
				(width 0.15)
				(type solid)
			)
			(layer "F.SilkS")
		)
		(fp_circle
			(center -1.25 -1.5)
			(end -1.2 -1.5)
			(stroke
				(width 0.15)
				(type solid)
			)
			(fill solid)
			(layer "F.SilkS")
		)
		(fp_rect
			(start 1.9 -1.76)
			(end -1.9 1.75)
			(stroke
				(width 0.05)
				(type solid)
			)
			(fill none)
			(layer "F.CrtYd")
		)
		(fp_line
			(start -0.398 -1.526)
			(end -0.874 -1.05)
			(stroke
				(width 0.15)
				(type solid)
			)
			(layer "F.Fab")
		)
		(fp_rect
			(start 0.874 1.523)
			(end -0.873 -1.525)
			(stroke
				(width 0.15)
				(type solid)
			)
			(fill none)
			(layer "F.Fab")
		)
		(fp_text user "Author: Antmicro"
			(at -1.898 5.499 0)
			(layer "F.Fab")
			(hide yes)
			(effects
				(font
					(size 0.7 0.7)
					(thickness 0.15)
				)
				(justify right bottom)
			)
		)
		(fp_text user "${REFERENCE}"
			(at -1.898 4.299 0)
			(layer "F.Fab")
			(hide yes)
			(effects
				(font
					(size 0.7 0.7)
					(thickness 0.15)
				)
				(justify right bottom)
			)
		)
		(fp_text user "License: Apache-2.0"
			(at -1.898 6.7 0)
			(layer "F.Fab")
			(hide yes)
			(effects
				(font
					(size 0.7 0.7)
					(thickness 0.15)
				)
				(justify right bottom)
			)
		)
		(pad "1" smd rect
			(at -1.351 -0.951 90)
			(size 0.55 1)
			(layers "F.Cu" "F.Paste" "F.Mask")
			(net 11 "+1V8")
			(pinfunction "VIN")
			(pintype "power_in")
		)
		(pad "2" smd rect
			(at -1.351 0 90)
			(size 0.55 1)
			(layers "F.Cu" "F.Paste" "F.Mask")
			(net 1 "GND")
			(pinfunction "GND")
			(pintype "power_in")
		)
		(pad "3" smd rect
			(at -1.351 0.949 90)
			(size 0.55 1)
			(layers "F.Cu" "F.Paste" "F.Mask")
			(net 11 "+1V8")
			(pinfunction "EN")
			(pintype "input")
		)
		(pad "4" smd rect
			(at 1.35 0.949 90)
			(size 0.55 1)
			(layers "F.Cu" "F.Paste" "F.Mask")
			(net 86 "unconnected-(U5-NC-Pad4)")
			(pinfunction "NC")
			(pintype "no_connect")
		)
		(pad "5" smd rect
			(at 1.35 -0.951 90)
			(size 0.55 1)
			(layers "F.Cu" "F.Paste" "F.Mask")
			(net 12 "+1V2")
			(pinfunction "VOUT")
			(pintype "power_out")
		)
	)
)
